(kicad_pcb
	(version 20260206)
	(generator "pcbnew")
	(generator_version "10.0")
	(general
		(thickness 1.6)
		(legacy_teardrops no)
	)
	(paper "A4")
	(title_block
		(title "Wiwynn_Tioga_Pass_MB.brd")
		(comment 1 "Tioga Pass / footprints 4702-4708 of 4770")
	)
	(layers
		(0 "F.Cu" signal "TOP")
		(4 "In1.Cu" signal "L2GND")
		(6 "In2.Cu" signal "L3")
		(8 "In3.Cu" signal "L4GND")
		(10 "In4.Cu" signal "L5")
		(12 "In5.Cu" signal "L6GND")
		(14 "In6.Cu" signal "L7VCC")
		(16 "In7.Cu" signal "L8VCC")
		(18 "In8.Cu" signal "L9GND")
		(20 "In9.Cu" signal "L10")
		(22 "In10.Cu" signal "L11GND")
		(24 "In11.Cu" signal "L12")
		(26 "In12.Cu" signal "L13GND")
		(2 "B.Cu" signal "BOTTOM")
		(9 "F.Adhes" user "F.Adhesive")
		(11 "B.Adhes" user "B.Adhesive")
		(13 "F.Paste" user "Package Geometry/Pastemask Top")
		(15 "B.Paste" user "Package Geometry/Pastemask Bottom")
		(5 "F.SilkS" user "Ref Des/Silkscreen Top")
		(7 "B.SilkS" user "Ref Des/Silkscreen Bottom")
		(1 "F.Mask" user "Board Geometry/Soldermask Top")
		(3 "B.Mask" user "Board Geometry/Soldermask Bottom")
		(17 "Dwgs.User" user "User.Drawings")
		(19 "Cmts.User" user "User.Comments")
		(21 "Eco1.User" user "User.Eco1")
		(23 "Eco2.User" user "User.Eco2")
		(25 "Edge.Cuts" user "Board Geometry/Outline")
		(27 "Margin" user)
		(31 "F.CrtYd" user "Package Geometry/Place Bound Top")
		(29 "B.CrtYd" user "Package Geometry/Place Bound Bottom")
		(35 "F.Fab" user "Ref Des/Assembly Top")
		(33 "B.Fab" user "Ref Des/Assembly Bottom")
	)
	(footprint ""
		(layer "B.Cu")
		(at 485.58577 -58.103262 180)
		(property "Reference" "L30W1"
			(at -0.127 -1.07188 180)
			(unlocked yes)
			(layer "B.SilkS")
			(effects
				(font
					(size 0.4064 0.254)
					(thickness 0.1524)
				)
				(justify left mirror)
			)
		)
		(property "Value" ""
			(at 0 0 0)
			(layer "B.Fab")
			(effects
				(font
					(size 1.27 1.27)
				)
				(justify mirror)
			)
		)
		(duplicate_pad_numbers_are_jumpers no)
		(fp_rect
			(start 0.08382 1.09982)
			(end -2.11582 -0.29972)
			(stroke
				(width 0)
				(type default)
			)
			(fill no)
			(layer "B.CrtYd")
		)
		(fp_line
			(start 0.08382 1.09982)
			(end 0.08382 -0.29972)
			(stroke
				(width 0.1)
				(type default)
			)
			(layer "B.Fab")
		)
		(fp_line
			(start 0.08382 -0.29972)
			(end -2.11582 -0.29972)
			(stroke
				(width 0.1)
				(type default)
			)
			(layer "B.Fab")
		)
		(fp_line
			(start -2.11582 1.09982)
			(end 0.08382 1.09982)
			(stroke
				(width 0.1)
				(type default)
			)
			(layer "B.Fab")
		)
		(fp_line
			(start -2.11582 -0.29972)
			(end -2.11582 1.09982)
			(stroke
				(width 0.1)
				(type default)
			)
			(layer "B.Fab")
		)
		(pad "1" smd rect
			(at 0 0)
			(size 1.27 0.508)
			(layers "B.Cu" "B.Mask" "B.Paste")
			(net "USB3_P01_RXP")
		)
		(pad "2" smd rect
			(at -2.032 0)
			(size 1.27 0.508)
			(layers "B.Cu" "B.Mask" "B.Paste")
			(net "USB3_P01_FB_RXP")
		)
		(pad "3" smd rect
			(at -2.032 0.8001)
			(size 1.27 0.508)
			(layers "B.Cu" "B.Mask" "B.Paste")
			(net "USB3_P01_FB_RXN")
		)
		(pad "4" smd rect
			(at 0 0.8001)
			(size 1.27 0.508)
			(layers "B.Cu" "B.Mask" "B.Paste")
			(net "USB3_P01_RXN")
		)
		(zone
			(layer "B.Cu")
			(hatch none 0.5)
			(connect_pads
				(clearance 0)
			)
			(min_thickness 0.25)
			(keepout
				(tracks not_allowed)
				(vias allowed)
				(pads allowed)
				(copperpour not_allowed)
				(footprints allowed)
			)
			(placement
				(enabled no)
				(sheetname "")
			)
			(fill
				(thermal_gap 0.5)
				(thermal_bridge_width 0.5)
				(island_removal_mode 0)
			)
			(polygon
				(pts
					(xy 484.95077 -58.649362) (xy 484.95077 -58.357262) (xy 486.22077 -58.357262) (xy 486.22077 -58.649362)
				)
			)
		)
		(zone
			(layer "B.Cu")
			(hatch none 0.5)
			(connect_pads
				(clearance 0)
			)
			(min_thickness 0.25)
			(keepout
				(tracks not_allowed)
				(vias allowed)
				(pads allowed)
				(copperpour not_allowed)
				(footprints allowed)
			)
			(placement
				(enabled no)
				(sheetname "")
			)
			(fill
				(thermal_gap 0.5)
				(thermal_bridge_width 0.5)
				(island_removal_mode 0)
			)
			(polygon
				(pts
					(xy 486.22077 -59.157362) (xy 486.98277 -59.157362) (xy 486.98277 -57.849262) (xy 486.22077 -57.849262)
				)
			)
		)
		(zone
			(layer "B.Cu")
			(hatch none 0.5)
			(connect_pads
				(clearance 0)
			)
			(min_thickness 0.25)
			(keepout
				(tracks allowed)
				(vias not_allowed)
				(pads allowed)
				(copperpour not_allowed)
				(footprints allowed)
			)
			(placement
				(enabled no)
				(sheetname "")
			)
			(fill
				(thermal_gap 0.5)
				(thermal_bridge_width 0.5)
				(island_removal_mode 0)
			)
			(polygon
				(pts
					(xy 486.22077 -57.849262) (xy 486.22077 -59.157362) (xy 486.98277 -59.157362) (xy 486.98277 -57.849262)
				)
			)
		)
	)
	(footprint ""
		(layer "B.Cu")
		(at 421.386 -14.9352 90)
		(property "Reference" "R2T7"
			(at 0 0 90)
			(layer "B.SilkS")
			(hide yes)
			(effects
				(font
					(size 1.27 1.27)
				)
				(justify mirror)
			)
		)
		(property "Value" ""
			(at 0 0 90)
			(layer "B.Fab")
			(effects
				(font
					(size 1.27 1.27)
				)
				(justify mirror)
			)
		)
		(duplicate_pad_numbers_are_jumpers no)
		(fp_poly
			(pts
				(xy 0.2794 -0.1016) (xy -0.2794 -0.1016) (xy -0.2794 0.9906) (xy 0.2794 0.9906)
			)
			(stroke
				(width 0)
				(type default)
			)
			(fill no)
			(layer "B.CrtYd")
		)
		(fp_line
			(start 0.2794 -0.1016)
			(end 0.2794 0.9906)
			(stroke
				(width 0.1)
				(type default)
			)
			(layer "B.Fab")
		)
		(fp_line
			(start -0.2794 -0.1016)
			(end 0.2794 -0.1016)
			(stroke
				(width 0.1)
				(type default)
			)
			(layer "B.Fab")
		)
		(fp_line
			(start 0.2794 0.9906)
			(end -0.2794 0.9906)
			(stroke
				(width 0.1)
				(type default)
			)
			(layer "B.Fab")
		)
		(fp_line
			(start -0.2794 0.9906)
			(end -0.2794 -0.1016)
			(stroke
				(width 0.1)
				(type default)
			)
			(layer "B.Fab")
		)
		(pad "1" smd rect
			(at 0 0 270)
			(size 0.508 0.508)
			(layers "B.Cu" "B.Mask" "B.Paste")
			(net "P3V3_STBY")
		)
		(pad "2" smd rect
			(at 0 0.889 270)
			(size 0.508 0.508)
			(layers "B.Cu" "B.Mask" "B.Paste")
			(net "H_CPU0_FAST_WAKE_LVT3_N")
		)
		(zone
			(layer "B.Cu")
			(hatch none 0.5)
			(connect_pads
				(clearance 0)
			)
			(min_thickness 0.25)
			(keepout
				(tracks allowed)
				(vias not_allowed)
				(pads allowed)
				(copperpour not_allowed)
				(footprints allowed)
			)
			(placement
				(enabled no)
				(sheetname "")
			)
			(fill
				(thermal_gap 0.5)
				(thermal_bridge_width 0.5)
				(island_removal_mode 0)
			)
			(polygon
				(pts
					(xy 421.64 -15.1892) (xy 421.64 -14.6812) (xy 422.021 -14.6812) (xy 422.021 -15.1892)
				)
			)
		)
		(zone
			(layer "B.Cu")
			(hatch none 0.5)
			(connect_pads
				(clearance 0)
			)
			(min_thickness 0.25)
			(keepout
				(tracks not_allowed)
				(vias allowed)
				(pads allowed)
				(copperpour not_allowed)
				(footprints allowed)
			)
			(placement
				(enabled no)
				(sheetname "")
			)
			(fill
				(thermal_gap 0.5)
				(thermal_bridge_width 0.5)
				(island_removal_mode 0)
			)
			(polygon
				(pts
					(xy 422.021 -15.1892) (xy 422.021 -14.6812) (xy 421.64 -14.6812) (xy 421.64 -15.1892)
				)
			)
		)
	)
	(footprint ""
		(layer "B.Cu")
		(at 276.836886 -73.51014)
		(property "Reference" "C4P7"
			(at 0 0 0)
			(layer "B.SilkS")
			(hide yes)
			(effects
				(font
					(size 1.27 1.27)
				)
				(justify mirror)
			)
		)
		(property "Value" ""
			(at 0 0 0)
			(layer "B.Fab")
			(effects
				(font
					(size 1.27 1.27)
				)
				(justify mirror)
			)
		)
		(duplicate_pad_numbers_are_jumpers no)
		(fp_poly
			(pts
				(xy 0.7239 -0.2159) (xy -0.7239 -0.2159) (xy -0.7239 1.9939) (xy 0.7239 1.9939)
			)
			(stroke
				(width 0)
				(type default)
			)
			(fill no)
			(layer "B.CrtYd")
		)
		(fp_line
			(start -0.7239 -0.2159)
			(end 0.7239 -0.2159)
			(stroke
				(width 0.1)
				(type default)
			)
			(layer "B.Fab")
		)
		(fp_line
			(start -0.7239 1.9939)
			(end -0.7239 -0.2159)
			(stroke
				(width 0.1)
				(type default)
			)
			(layer "B.Fab")
		)
		(fp_line
			(start 0.7239 -0.2159)
			(end 0.7239 1.9939)
			(stroke
				(width 0.1)
				(type default)
			)
			(layer "B.Fab")
		)
		(fp_line
			(start 0.7239 1.9939)
			(end -0.7239 1.9939)
			(stroke
				(width 0.1)
				(type default)
			)
			(layer "B.Fab")
		)
		(pad "1" smd rect
			(at 0 0 180)
			(size 1.27 1.016)
			(layers "B.Cu" "B.Mask" "B.Paste")
			(net "PVCCMCP_CPU0")
		)
		(pad "2" smd rect
			(at 0 1.778 180)
			(size 1.27 1.016)
			(layers "B.Cu" "B.Mask" "B.Paste")
			(net "GND")
		)
		(zone
			(layer "B.Cu")
			(hatch none 0.5)
			(connect_pads
				(clearance 0)
			)
			(min_thickness 0.25)
			(keepout
				(tracks not_allowed)
				(vias allowed)
				(pads allowed)
				(copperpour not_allowed)
				(footprints allowed)
			)
			(placement
				(enabled no)
				(sheetname "")
			)
			(fill
				(thermal_gap 0.5)
				(thermal_bridge_width 0.5)
				(island_removal_mode 0)
			)
			(polygon
				(pts
					(xy 277.471886 -73.00214) (xy 276.201886 -73.00214) (xy 276.201886 -72.24014) (xy 277.471886 -72.24014)
				)
			)
		)
	)
	(footprint ""
		(layer "B.Cu")
		(at 500.824246 -38.069774 -90)
		(property "Reference" "C1T10"
			(at 0 0 90)
			(layer "B.SilkS")
			(hide yes)
			(effects
				(font
					(size 1.27 1.27)
				)
				(justify mirror)
			)
		)
		(property "Value" ""
			(at 0 0 90)
			(layer "B.Fab")
			(effects
				(font
					(size 1.27 1.27)
				)
				(justify mirror)
			)
		)
		(duplicate_pad_numbers_are_jumpers no)
		(fp_poly
			(pts
				(xy -0.3048 -0.1016) (xy -0.3048 0.9906) (xy 0.3048 0.9906) (xy 0.3048 -0.1016)
			)
			(stroke
				(width 0)
				(type default)
			)
			(fill no)
			(layer "B.CrtYd")
		)
		(fp_line
			(start -0.3048 0.9906)
			(end -0.3048 -0.1016)
			(stroke
				(width 0.1)
				(type default)
			)
			(layer "B.Fab")
		)
		(fp_line
			(start 0.3048 0.9906)
			(end -0.3048 0.9906)
			(stroke
				(width 0.1)
				(type default)
			)
			(layer "B.Fab")
		)
		(fp_line
			(start -0.3048 -0.1016)
			(end 0.3048 -0.1016)
			(stroke
				(width 0.1)
				(type default)
			)
			(layer "B.Fab")
		)
		(fp_line
			(start 0.3048 -0.1016)
			(end 0.3048 0.9906)
			(stroke
				(width 0.1)
				(type default)
			)
			(layer "B.Fab")
		)
		(pad "1" smd rect
			(at 0 0 90)
			(size 0.508 0.508)
			(layers "B.Cu" "B.Mask" "B.Paste")
			(net "P3V3_STBY")
		)
		(pad "2" smd rect
			(at 0 0.889 90)
			(size 0.508 0.508)
			(layers "B.Cu" "B.Mask" "B.Paste")
			(net "GND")
		)
		(zone
			(layer "B.Cu")
			(hatch none 0.5)
			(connect_pads
				(clearance 0)
			)
			(min_thickness 0.25)
			(keepout
				(tracks not_allowed)
				(vias allowed)
				(pads allowed)
				(copperpour not_allowed)
				(footprints allowed)
			)
			(placement
				(enabled no)
				(sheetname "")
			)
			(fill
				(thermal_gap 0.5)
				(thermal_bridge_width 0.5)
				(island_removal_mode 0)
			)
			(polygon
				(pts
					(xy 500.189246 -37.815774) (xy 500.189246 -38.323774) (xy 500.570246 -38.323774) (xy 500.570246 -37.815774)
				)
			)
		)
		(zone
			(layer "B.Cu")
			(hatch none 0.5)
			(connect_pads
				(clearance 0)
			)
			(min_thickness 0.25)
			(keepout
				(tracks allowed)
				(vias not_allowed)
				(pads allowed)
				(copperpour not_allowed)
				(footprints allowed)
			)
			(placement
				(enabled no)
				(sheetname "")
			)
			(fill
				(thermal_gap 0.5)
				(thermal_bridge_width 0.5)
				(island_removal_mode 0)
			)
			(polygon
				(pts
					(xy 500.570246 -37.815774) (xy 500.570246 -38.323774) (xy 500.189246 -38.323774) (xy 500.189246 -37.815774)
				)
			)
		)
	)
	(footprint ""
		(layer "B.Cu")
		(at 373.520716 -59.289442 180)
		(property "Reference" "R3P49"
			(at 0 0 0)
			(layer "B.SilkS")
			(hide yes)
			(effects
				(font
					(size 1.27 1.27)
				)
				(justify mirror)
			)
		)
		(property "Value" ""
			(at 0 0 0)
			(layer "B.Fab")
			(effects
				(font
					(size 1.27 1.27)
				)
				(justify mirror)
			)
		)
		(duplicate_pad_numbers_are_jumpers no)
		(fp_poly
			(pts
				(xy 0.2794 -0.1016) (xy -0.2794 -0.1016) (xy -0.2794 0.9906) (xy 0.2794 0.9906)
			)
			(stroke
				(width 0)
				(type default)
			)
			(fill no)
			(layer "B.CrtYd")
		)
		(fp_line
			(start 0.2794 0.9906)
			(end -0.2794 0.9906)
			(stroke
				(width 0.1)
				(type default)
			)
			(layer "B.Fab")
		)
		(fp_line
			(start 0.2794 -0.1016)
			(end 0.2794 0.9906)
			(stroke
				(width 0.1)
				(type default)
			)
			(layer "B.Fab")
		)
		(fp_line
			(start -0.2794 0.9906)
			(end -0.2794 -0.1016)
			(stroke
				(width 0.1)
				(type default)
			)
			(layer "B.Fab")
		)
		(fp_line
			(start -0.2794 -0.1016)
			(end 0.2794 -0.1016)
			(stroke
				(width 0.1)
				(type default)
			)
			(layer "B.Fab")
		)
		(pad "1" smd rect
			(at 0 0)
			(size 0.508 0.508)
			(layers "B.Cu" "B.Mask" "B.Paste")
			(net "P0V7_GTL2104_VREF_1")
		)
		(pad "2" smd rect
			(at 0 0.889)
			(size 0.508 0.508)
			(layers "B.Cu" "B.Mask" "B.Paste")
			(net "GND")
		)
		(zone
			(layer "B.Cu")
			(hatch none 0.5)
			(connect_pads
				(clearance 0)
			)
			(min_thickness 0.25)
			(keepout
				(tracks not_allowed)
				(vias allowed)
				(pads allowed)
				(copperpour not_allowed)
				(footprints allowed)
			)
			(placement
				(enabled no)
				(sheetname "")
			)
			(fill
				(thermal_gap 0.5)
				(thermal_bridge_width 0.5)
				(island_removal_mode 0)
			)
			(polygon
				(pts
					(xy 373.266716 -59.924442) (xy 373.774716 -59.924442) (xy 373.774716 -59.543442) (xy 373.266716 -59.543442)
				)
			)
		)
		(zone
			(layer "B.Cu")
			(hatch none 0.5)
			(connect_pads
				(clearance 0)
			)
			(min_thickness 0.25)
			(keepout
				(tracks allowed)
				(vias not_allowed)
				(pads allowed)
				(copperpour not_allowed)
				(footprints allowed)
			)
			(placement
				(enabled no)
				(sheetname "")
			)
			(fill
				(thermal_gap 0.5)
				(thermal_bridge_width 0.5)
				(island_removal_mode 0)
			)
			(polygon
				(pts
					(xy 373.266716 -59.543442) (xy 373.774716 -59.543442) (xy 373.774716 -59.924442) (xy 373.266716 -59.924442)
				)
			)
		)
	)
	(footprint ""
		(layer "B.Cu")
		(at 164.973 -80.391 90)
		(property "Reference" "C6P12"
			(at 0 0 90)
			(layer "B.SilkS")
			(hide yes)
			(effects
				(font
					(size 1.27 1.27)
				)
				(justify mirror)
			)
		)
		(property "Value" ""
			(at 0 0 90)
			(layer "B.Fab")
			(effects
				(font
					(size 1.27 1.27)
				)
				(justify mirror)
			)
		)
		(duplicate_pad_numbers_are_jumpers no)
		(fp_poly
			(pts
				(xy -0.3048 -0.1016) (xy -0.3048 0.9906) (xy 0.3048 0.9906) (xy 0.3048 -0.1016)
			)
			(stroke
				(width 0)
				(type default)
			)
			(fill no)
			(layer "B.CrtYd")
		)
		(fp_line
			(start 0.3048 -0.1016)
			(end 0.3048 0.9906)
			(stroke
				(width 0.1)
				(type default)
			)
			(layer "B.Fab")
		)
		(fp_line
			(start -0.3048 -0.1016)
			(end 0.3048 -0.1016)
			(stroke
				(width 0.1)
				(type default)
			)
			(layer "B.Fab")
		)
		(fp_line
			(start 0.3048 0.9906)
			(end -0.3048 0.9906)
			(stroke
				(width 0.1)
				(type default)
			)
			(layer "B.Fab")
		)
		(fp_line
			(start -0.3048 0.9906)
			(end -0.3048 -0.1016)
			(stroke
				(width 0.1)
				(type default)
			)
			(layer "B.Fab")
		)
		(pad "1" smd rect
			(at 0 0 270)
			(size 0.508 0.508)
			(layers "B.Cu" "B.Mask" "B.Paste")
			(net "P3V3_DB1200")
		)
		(pad "2" smd rect
			(at 0 0.889 270)
			(size 0.508 0.508)
			(layers "B.Cu" "B.Mask" "B.Paste")
			(net "GND")
		)
		(zone
			(layer "B.Cu")
			(hatch none 0.5)
			(connect_pads
				(clearance 0)
			)
			(min_thickness 0.25)
			(keepout
				(tracks allowed)
				(vias not_allowed)
				(pads allowed)
				(copperpour not_allowed)
				(footprints allowed)
			)
			(placement
				(enabled no)
				(sheetname "")
			)
			(fill
				(thermal_gap 0.5)
				(thermal_bridge_width 0.5)
				(island_removal_mode 0)
			)
			(polygon
				(pts
					(xy 165.227 -80.645) (xy 165.227 -80.137) (xy 165.608 -80.137) (xy 165.608 -80.645)
				)
			)
		)
		(zone
			(layer "B.Cu")
			(hatch none 0.5)
			(connect_pads
				(clearance 0)
			)
			(min_thickness 0.25)
			(keepout
				(tracks not_allowed)
				(vias allowed)
				(pads allowed)
				(copperpour not_allowed)
				(footprints allowed)
			)
			(placement
				(enabled no)
				(sheetname "")
			)
			(fill
				(thermal_gap 0.5)
				(thermal_bridge_width 0.5)
				(island_removal_mode 0)
			)
			(polygon
				(pts
					(xy 165.608 -80.645) (xy 165.608 -80.137) (xy 165.227 -80.137) (xy 165.227 -80.645)
				)
			)
		)
	)
	(footprint ""
		(layer "B.Cu")
		(at 482.727 -53.1368 -90)
		(property "Reference" "R8E17"
			(at 0 0 90)
			(layer "B.SilkS")
			(hide yes)
			(effects
				(font
					(size 1.27 1.27)
				)
				(justify mirror)
			)
		)
		(property "Value" ""
			(at 0 0 90)
			(layer "B.Fab")
			(effects
				(font
					(size 1.27 1.27)
				)
				(justify mirror)
			)
		)
		(duplicate_pad_numbers_are_jumpers no)
		(fp_poly
			(pts
				(xy 0.2794 -0.1016) (xy -0.2794 -0.1016) (xy -0.2794 0.9906) (xy 0.2794 0.9906)
			)
			(stroke
				(width 0)
				(type default)
			)
			(fill no)
			(layer "B.CrtYd")
		)
		(fp_line
			(start -0.2794 0.9906)
			(end -0.2794 -0.1016)
			(stroke
				(width 0.1)
				(type default)
			)
			(layer "B.Fab")
		)
		(fp_line
			(start 0.2794 0.9906)
			(end -0.2794 0.9906)
			(stroke
				(width 0.1)
				(type default)
			)
			(layer "B.Fab")
		)
		(fp_line
			(start -0.2794 -0.1016)
			(end 0.2794 -0.1016)
			(stroke
				(width 0.1)
				(type default)
			)
			(layer "B.Fab")
		)
		(fp_line
			(start 0.2794 -0.1016)
			(end 0.2794 0.9906)
			(stroke
				(width 0.1)
				(type default)
			)
			(layer "B.Fab")
		)
		(pad "1" smd rect
			(at 0 0 90)
			(size 0.508 0.508)
			(layers "B.Cu" "B.Mask" "B.Paste")
			(net "IRQ_LVC3_WAKE_R_N")
		)
		(pad "2" smd rect
			(at 0 0.889 90)
			(size 0.508 0.508)
			(layers "B.Cu" "B.Mask" "B.Paste")
			(net "IRQ_LVC3_WAKE_N")
		)
		(zone
			(layer "B.Cu")
			(hatch none 0.5)
			(connect_pads
				(clearance 0)
			)
			(min_thickness 0.25)
			(keepout
				(tracks not_allowed)
				(vias allowed)
				(pads allowed)
				(copperpour not_allowed)
				(footprints allowed)
			)
			(placement
				(enabled no)
				(sheetname "")
			)
			(fill
				(thermal_gap 0.5)
				(thermal_bridge_width 0.5)
				(island_removal_mode 0)
			)
			(polygon
				(pts
					(xy 482.092 -52.8828) (xy 482.092 -53.3908) (xy 482.473 -53.3908) (xy 482.473 -52.8828)
				)
			)
		)
		(zone
			(layer "B.Cu")
			(hatch none 0.5)
			(connect_pads
				(clearance 0)
			)
			(min_thickness 0.25)
			(keepout
				(tracks allowed)
				(vias not_allowed)
				(pads allowed)
				(copperpour not_allowed)
				(footprints allowed)
			)
			(placement
				(enabled no)
				(sheetname "")
			)
			(fill
				(thermal_gap 0.5)
				(thermal_bridge_width 0.5)
				(island_removal_mode 0)
			)
			(polygon
				(pts
					(xy 482.473 -52.8828) (xy 482.473 -53.3908) (xy 482.092 -53.3908) (xy 482.092 -52.8828)
				)
			)
		)
	)
)
